(kicad_pcb
	(version 20260206)
	(generator "pcbnew")
	(generator_version "10.0")
	(general
		(thickness 1.6)
		(legacy_teardrops no)
	)
	(paper "A4")
	(title_block
		(title "panther-plus-userver — 13130-1b_20150205.brd")
		(comment 1 "Honey Badger (Wiwynn) / footprint 894 of 1509 (DIMM1), pads 198-204 of 210")
	)
	(layers
		(0 "F.Cu" signal "TOP")
		(4 "In1.Cu" signal "L2")
		(6 "In2.Cu" signal "L3")
		(8 "In3.Cu" signal "L4")
		(10 "In4.Cu" signal "L5")
		(12 "In5.Cu" signal "L6")
		(14 "In6.Cu" signal "L7")
		(16 "In7.Cu" signal "L8")
		(18 "In8.Cu" signal "L9")
		(20 "In9.Cu" signal "L10")
		(22 "In10.Cu" signal "L11")
		(2 "B.Cu" signal "BOTTOM")
		(9 "F.Adhes" user "F.Adhesive")
		(11 "B.Adhes" user "B.Adhesive")
		(13 "F.Paste" user "Package Geometry/Pastemask Top")
		(15 "B.Paste" user "Package Geometry/Pastemask Bottom")
		(5 "F.SilkS" user "Ref Des/Silkscreen Top")
		(7 "B.SilkS" user "Ref Des/Silkscreen Bottom")
		(1 "F.Mask" user "Board Geometry/Soldermask Top")
		(3 "B.Mask" user "Board Geometry/Soldermask Bottom")
		(17 "Dwgs.User" user "User.Drawings")
		(19 "Cmts.User" user "User.Comments")
		(21 "Eco1.User" user "User.Eco1")
		(23 "Eco2.User" user "User.Eco2")
		(25 "Edge.Cuts" user "Board Geometry/Outline")
		(27 "Margin" user)
		(31 "F.CrtYd" user "Package Geometry/Place Bound Top")
		(29 "B.CrtYd" user "Package Geometry/Place Bound Bottom")
		(35 "F.Fab" user "Ref Des/Assembly Top")
		(33 "B.Fab" user "Ref Des/Assembly Bottom")
	)
	(footprint ""
		(layer "B.Cu")
		(at 158.500064 -66.699892 180)
		(property "Reference" "DIMM1"
			(at 0 0 0)
			(layer "B.SilkS")
			(hide yes)
			(effects
				(font
					(size 1.27 1.27)
				)
				(justify mirror)
			)
		)
		(property "Value" "DDR3-204P-142-COLAY-1-GP-U"
			(at 41.312338 -16.676878 180)
			(unlocked yes)
			(layer "B.Fab")
			(hide yes)
			(effects
				(font
					(size 1.016 1.016)
					(thickness 0.1524)
				)
				(justify mirror)
			)
		)
		(property "Device Type" "AS0A626-J8R6-7H-COLAY-1"
			(at 41.312338 -18.200878 180)
			(unlocked yes)
			(layer "B.Fab")
			(hide yes)
			(effects
				(font
					(size 1.016 1.016)
					(thickness 0.1524)
				)
				(justify mirror)
			)
		)
		(duplicate_pad_numbers_are_jumpers no)
		(pad "196" smd custom
			(at 29.249878 4.100068)
			(size 0.1143 0.1143)
			(layers "B.Cu" "B.Mask" "B.Paste")
			(net "GND")
			(options
				(clearance outline)
				(anchor circle)
			)
			(primitives
				(gr_poly
					(pts
						(xy 0 -0.9017) (xy -0.03175 -0.89916) (xy -0.0635 -0.889) (xy -0.09144 -0.87376) (xy -0.11684 -0.85344)
						(xy -0.13716 -0.82804) (xy -0.1524 -0.8001) (xy -0.16256 -0.76835) (xy -0.1651 -0.7366) (xy -0.1651 -0.11938)
						(xy -0.17272 -0.11176) (xy -0.19812 -0.0762) (xy -0.2032 -0.06604) (xy -0.20701 -0.05715) (xy -0.21209 -0.04699)
						(xy -0.2159 -0.03683) (xy -0.21844 -0.02667) (xy -0.22225 -0.01524) (xy -0.22352 -0.00508) (xy -0.22606 0.00508)
						(xy -0.22733 0.01651) (xy -0.22733 0.02667) (xy -0.2286 0.0381) (xy -0.22733 0.04953) (xy -0.22733 0.05969)
						(xy -0.22606 0.07112) (xy -0.22352 0.08128) (xy -0.22225 0.09144) (xy -0.21844 0.10287) (xy -0.2159 0.11303)
						(xy -0.21209 0.12319) (xy -0.20701 0.13335) (xy -0.2032 0.14224) (xy -0.19812 0.1524) (xy -0.17272 0.18796)
						(xy -0.1651 0.19558) (xy -0.1651 0.7366) (xy -0.16256 0.76835) (xy -0.1524 0.8001) (xy -0.13716 0.82804)
						(xy -0.11684 0.85344) (xy -0.09144 0.87376) (xy -0.0635 0.889) (xy -0.03175 0.89916) (xy 0 0.9017)
						(xy 0.03175 0.89916) (xy 0.0635 0.889) (xy 0.09144 0.87376) (xy 0.11684 0.85344) (xy 0.13716 0.82804)
						(xy 0.1524 0.8001) (xy 0.16256 0.76835) (xy 0.1651 0.7366) (xy 0.1651 0.19685) (xy 0.17272 0.18923)
						(xy 0.17907 0.18034) (xy 0.18669 0.17145) (xy 0.19177 0.16256) (xy 0.19812 0.15367) (xy 0.20828 0.13335)
						(xy 0.21971 0.10287) (xy 0.22225 0.09271) (xy 0.22479 0.08128) (xy 0.22606 0.07112) (xy 0.2286 0.05969)
						(xy 0.2286 0.01651) (xy 0.22606 0.00508) (xy 0.22479 -0.00508) (xy 0.22225 -0.01651) (xy 0.21971 -0.02667)
						(xy 0.20828 -0.05715) (xy 0.19812 -0.07747) (xy 0.19177 -0.08636) (xy 0.18669 -0.09525) (xy 0.17907 -0.10414)
						(xy 0.17272 -0.11303) (xy 0.1651 -0.12065) (xy 0.1651 -0.7366) (xy 0.16256 -0.76835) (xy 0.1524 -0.8001)
						(xy 0.13716 -0.82804) (xy 0.11684 -0.85344) (xy 0.09144 -0.87376) (xy 0.0635 -0.889) (xy 0.03175 -0.89916)
					)
					(width 0)
					(fill yes)
				)
			)
		)
		(pad "197" smd custom
			(at 29.550106 -4.100068)
			(size 0.1143 0.1143)
			(layers "B.Cu" "B.Mask" "B.Paste")
			(net "CHA_0_SA0")
			(options
				(clearance outline)
				(anchor circle)
			)
			(primitives
				(gr_poly
					(pts
						(xy 0 -0.9017) (xy -0.03175 -0.89916) (xy -0.0635 -0.889) (xy -0.09144 -0.87376) (xy -0.11684 -0.85344)
						(xy -0.13716 -0.82804) (xy -0.1524 -0.8001) (xy -0.16256 -0.76835) (xy -0.1651 -0.7366) (xy -0.1651 -0.44958)
						(xy -0.17272 -0.44196) (xy -0.19812 -0.4064) (xy -0.2032 -0.39624) (xy -0.20701 -0.38735) (xy -0.21209 -0.37719)
						(xy -0.2159 -0.36703) (xy -0.21844 -0.35687) (xy -0.22225 -0.34544) (xy -0.22352 -0.33528) (xy -0.22606 -0.32512)
						(xy -0.22733 -0.31369) (xy -0.22733 -0.30353) (xy -0.2286 -0.2921) (xy -0.22733 -0.28067) (xy -0.22733 -0.27051)
						(xy -0.22606 -0.25908) (xy -0.22352 -0.24892) (xy -0.22225 -0.23876) (xy -0.21844 -0.22733) (xy -0.2159 -0.21717)
						(xy -0.21209 -0.20701) (xy -0.20701 -0.19685) (xy -0.2032 -0.18796) (xy -0.19812 -0.1778) (xy -0.17272 -0.14224)
						(xy -0.1651 -0.13462) (xy -0.1651 0.7366) (xy -0.16256 0.76835) (xy -0.1524 0.8001) (xy -0.13716 0.82804)
						(xy -0.11684 0.85344) (xy -0.09144 0.87376) (xy -0.0635 0.889) (xy -0.03175 0.89916) (xy 0 0.9017)
						(xy 0.03175 0.89916) (xy 0.0635 0.889) (xy 0.09144 0.87376) (xy 0.11684 0.85344) (xy 0.13716 0.82804)
						(xy 0.1524 0.8001) (xy 0.16256 0.76835) (xy 0.1651 0.7366) (xy 0.1651 -0.13462) (xy 0.17272 -0.14224)
						(xy 0.19812 -0.1778) (xy 0.2032 -0.18796) (xy 0.20701 -0.19685) (xy 0.21209 -0.20701) (xy 0.2159 -0.21717)
						(xy 0.21844 -0.22733) (xy 0.22225 -0.23876) (xy 0.22352 -0.24892) (xy 0.22606 -0.25908) (xy 0.22733 -0.27051)
						(xy 0.22733 -0.28067) (xy 0.2286 -0.2921) (xy 0.22733 -0.30353) (xy 0.22733 -0.31369) (xy 0.22606 -0.32512)
						(xy 0.22352 -0.33528) (xy 0.22225 -0.34544) (xy 0.21844 -0.35687) (xy 0.2159 -0.36703) (xy 0.21209 -0.37719)
						(xy 0.20701 -0.38735) (xy 0.2032 -0.39624) (xy 0.19812 -0.4064) (xy 0.17272 -0.44196) (xy 0.1651 -0.44958)
						(xy 0.1651 -0.7366) (xy 0.16256 -0.76835) (xy 0.1524 -0.8001) (xy 0.13716 -0.82804) (xy 0.11684 -0.85344)
						(xy 0.09144 -0.87376) (xy 0.0635 -0.889) (xy 0.03175 -0.89916)
					)
					(width 0)
					(fill yes)
				)
			)
		)
		(pad "198" smd custom
			(at 29.85008 4.100068)
			(size 0.1143 0.1143)
			(layers "B.Cu" "B.Mask" "B.Paste")
			(net "MEMORY_HOT_LV_R#")
			(options
				(clearance outline)
				(anchor circle)
			)
			(primitives
				(gr_poly
					(pts
						(xy 0 -0.9017) (xy -0.03175 -0.89916) (xy -0.0635 -0.889) (xy -0.09144 -0.87376) (xy -0.11684 -0.85344)
						(xy -0.13716 -0.82804) (xy -0.1524 -0.8001) (xy -0.16256 -0.76835) (xy -0.1651 -0.7366) (xy -0.1651 0.13462)
						(xy -0.17272 0.14224) (xy -0.19812 0.1778) (xy -0.2032 0.18796) (xy -0.20701 0.19685) (xy -0.21209 0.20701)
						(xy -0.2159 0.21717) (xy -0.21844 0.22733) (xy -0.22225 0.23876) (xy -0.22352 0.24892) (xy -0.22606 0.25908)
						(xy -0.22733 0.27051) (xy -0.22733 0.28067) (xy -0.2286 0.2921) (xy -0.22733 0.30353) (xy -0.22733 0.31369)
						(xy -0.22606 0.32512) (xy -0.22352 0.33528) (xy -0.22225 0.34544) (xy -0.21844 0.35687) (xy -0.2159 0.36703)
						(xy -0.21209 0.37719) (xy -0.20701 0.38735) (xy -0.2032 0.39624) (xy -0.19812 0.4064) (xy -0.17272 0.44196)
						(xy -0.1651 0.44958) (xy -0.1651 0.7366) (xy -0.16256 0.76835) (xy -0.1524 0.8001) (xy -0.13716 0.82804)
						(xy -0.11684 0.85344) (xy -0.09144 0.87376) (xy -0.0635 0.889) (xy -0.03175 0.89916) (xy 0 0.9017)
						(xy 0.03175 0.89916) (xy 0.0635 0.889) (xy 0.09144 0.87376) (xy 0.11684 0.85344) (xy 0.13716 0.82804)
						(xy 0.1524 0.8001) (xy 0.16256 0.76835) (xy 0.1651 0.7366) (xy 0.1651 0.44958) (xy 0.17272 0.44196)
						(xy 0.19812 0.4064) (xy 0.2032 0.39624) (xy 0.20701 0.38735) (xy 0.21209 0.37719) (xy 0.2159 0.36703)
						(xy 0.21844 0.35687) (xy 0.22225 0.34544) (xy 0.22352 0.33528) (xy 0.22606 0.32512) (xy 0.22733 0.31369)
						(xy 0.22733 0.30353) (xy 0.2286 0.2921) (xy 0.22733 0.28067) (xy 0.22733 0.27051) (xy 0.22606 0.25908)
						(xy 0.22352 0.24892) (xy 0.22225 0.23876) (xy 0.21844 0.22733) (xy 0.2159 0.21717) (xy 0.21209 0.20701)
						(xy 0.20701 0.19685) (xy 0.2032 0.18796) (xy 0.19812 0.1778) (xy 0.17272 0.14224) (xy 0.1651 0.13462)
						(xy 0.1651 -0.7366) (xy 0.16256 -0.76835) (xy 0.1524 -0.8001) (xy 0.13716 -0.82804) (xy 0.11684 -0.85344)
						(xy 0.09144 -0.87376) (xy 0.0635 -0.889) (xy 0.03175 -0.89916)
					)
					(width 0)
					(fill yes)
				)
			)
		)
		(pad "199" smd custom
			(at 30.150054 -4.100068)
			(size 0.1143 0.1143)
			(layers "B.Cu" "B.Mask" "B.Paste")
			(net "P3V3_STBY")
			(options
				(clearance outline)
				(anchor circle)
			)
			(primitives
				(gr_poly
					(pts
						(xy 0 -0.9017) (xy -0.03175 -0.89916) (xy -0.0635 -0.889) (xy -0.09144 -0.87376) (xy -0.11684 -0.85344)
						(xy -0.13716 -0.82804) (xy -0.1524 -0.8001) (xy -0.16256 -0.76835) (xy -0.1651 -0.7366) (xy -0.1651 -0.19685)
						(xy -0.17272 -0.18923) (xy -0.17907 -0.18034) (xy -0.18669 -0.17145) (xy -0.19177 -0.16256) (xy -0.19812 -0.15367)
						(xy -0.20828 -0.13335) (xy -0.21971 -0.10287) (xy -0.22225 -0.09271) (xy -0.22479 -0.08128) (xy -0.22606 -0.07112)
						(xy -0.2286 -0.05969) (xy -0.2286 -0.01651) (xy -0.22606 -0.00508) (xy -0.22479 0.00508) (xy -0.22225 0.01651)
						(xy -0.21971 0.02667) (xy -0.20828 0.05715) (xy -0.19812 0.07747) (xy -0.19177 0.08636) (xy -0.18669 0.09525)
						(xy -0.17907 0.10414) (xy -0.17272 0.11303) (xy -0.1651 0.12065) (xy -0.1651 0.7366) (xy -0.16256 0.76835)
						(xy -0.1524 0.8001) (xy -0.13716 0.82804) (xy -0.11684 0.85344) (xy -0.09144 0.87376) (xy -0.0635 0.889)
						(xy -0.03175 0.89916) (xy 0 0.9017) (xy 0.03175 0.89916) (xy 0.0635 0.889) (xy 0.09144 0.87376)
						(xy 0.11684 0.85344) (xy 0.13716 0.82804) (xy 0.1524 0.8001) (xy 0.16256 0.76835) (xy 0.1651 0.7366)
						(xy 0.1651 0.11938) (xy 0.17272 0.11176) (xy 0.19812 0.0762) (xy 0.2032 0.06604) (xy 0.20701 0.05715)
						(xy 0.21209 0.04699) (xy 0.2159 0.03683) (xy 0.21844 0.02667) (xy 0.22225 0.01524) (xy 0.22352 0.00508)
						(xy 0.22606 -0.00508) (xy 0.22733 -0.01651) (xy 0.22733 -0.02667) (xy 0.2286 -0.0381) (xy 0.22733 -0.04953)
						(xy 0.22733 -0.05969) (xy 0.22606 -0.07112) (xy 0.22352 -0.08128) (xy 0.22225 -0.09144) (xy 0.21844 -0.10287)
						(xy 0.2159 -0.11303) (xy 0.21209 -0.12319) (xy 0.20701 -0.13335) (xy 0.2032 -0.14224) (xy 0.19812 -0.1524)
						(xy 0.17272 -0.18796) (xy 0.1651 -0.19558) (xy 0.1651 -0.7366) (xy 0.16256 -0.76835) (xy 0.1524 -0.8001)
						(xy 0.13716 -0.82804) (xy 0.11684 -0.85344) (xy 0.09144 -0.87376) (xy 0.0635 -0.889) (xy 0.03175 -0.89916)
					)
					(width 0)
					(fill yes)
				)
			)
		)
		(pad "200" smd custom
			(at 30.450028 4.100068)
			(size 0.1143 0.1143)
			(layers "B.Cu" "B.Mask" "B.Paste")
			(net "SMB_M_A0_R_DATA")
			(options
				(clearance outline)
				(anchor circle)
			)
			(primitives
				(gr_poly
					(pts
						(xy 0 -0.9017) (xy -0.03175 -0.89916) (xy -0.0635 -0.889) (xy -0.09144 -0.87376) (xy -0.11684 -0.85344)
						(xy -0.13716 -0.82804) (xy -0.1524 -0.8001) (xy -0.16256 -0.76835) (xy -0.1651 -0.7366) (xy -0.1651 -0.11938)
						(xy -0.17272 -0.11176) (xy -0.19812 -0.0762) (xy -0.2032 -0.06604) (xy -0.20701 -0.05715) (xy -0.21209 -0.04699)
						(xy -0.2159 -0.03683) (xy -0.21844 -0.02667) (xy -0.22225 -0.01524) (xy -0.22352 -0.00508) (xy -0.22606 0.00508)
						(xy -0.22733 0.01651) (xy -0.22733 0.02667) (xy -0.2286 0.0381) (xy -0.22733 0.04953) (xy -0.22733 0.05969)
						(xy -0.22606 0.07112) (xy -0.22352 0.08128) (xy -0.22225 0.09144) (xy -0.21844 0.10287) (xy -0.2159 0.11303)
						(xy -0.21209 0.12319) (xy -0.20701 0.13335) (xy -0.2032 0.14224) (xy -0.19812 0.1524) (xy -0.17272 0.18796)
						(xy -0.1651 0.19558) (xy -0.1651 0.7366) (xy -0.16256 0.76835) (xy -0.1524 0.8001) (xy -0.13716 0.82804)
						(xy -0.11684 0.85344) (xy -0.09144 0.87376) (xy -0.0635 0.889) (xy -0.03175 0.89916) (xy 0 0.9017)
						(xy 0.03175 0.89916) (xy 0.0635 0.889) (xy 0.09144 0.87376) (xy 0.11684 0.85344) (xy 0.13716 0.82804)
						(xy 0.1524 0.8001) (xy 0.16256 0.76835) (xy 0.1651 0.7366) (xy 0.1651 0.19685) (xy 0.17272 0.18923)
						(xy 0.17907 0.18034) (xy 0.18669 0.17145) (xy 0.19177 0.16256) (xy 0.19812 0.15367) (xy 0.20828 0.13335)
						(xy 0.21971 0.10287) (xy 0.22225 0.09271) (xy 0.22479 0.08128) (xy 0.22606 0.07112) (xy 0.2286 0.05969)
						(xy 0.2286 0.01651) (xy 0.22606 0.00508) (xy 0.22479 -0.00508) (xy 0.22225 -0.01651) (xy 0.21971 -0.02667)
						(xy 0.20828 -0.05715) (xy 0.19812 -0.07747) (xy 0.19177 -0.08636) (xy 0.18669 -0.09525) (xy 0.17907 -0.10414)
						(xy 0.17272 -0.11303) (xy 0.1651 -0.12065) (xy 0.1651 -0.7366) (xy 0.16256 -0.76835) (xy 0.1524 -0.8001)
						(xy 0.13716 -0.82804) (xy 0.11684 -0.85344) (xy 0.09144 -0.87376) (xy 0.0635 -0.889) (xy 0.03175 -0.89916)
					)
					(width 0)
					(fill yes)
				)
			)
		)
		(pad "201" smd custom
			(at 30.750002 -4.100068)
			(size 0.1143 0.1143)
			(layers "B.Cu" "B.Mask" "B.Paste")
			(net "CHA_0_SA1")
			(options
				(clearance outline)
				(anchor circle)
			)
			(primitives
				(gr_poly
					(pts
						(xy 0 -0.9017) (xy -0.03175 -0.89916) (xy -0.0635 -0.889) (xy -0.09144 -0.87376) (xy -0.11684 -0.85344)
						(xy -0.13716 -0.82804) (xy -0.1524 -0.8001) (xy -0.16256 -0.76835) (xy -0.1651 -0.7366) (xy -0.1651 -0.44958)
						(xy -0.17272 -0.44196) (xy -0.19812 -0.4064) (xy -0.2032 -0.39624) (xy -0.20701 -0.38735) (xy -0.21209 -0.37719)
						(xy -0.2159 -0.36703) (xy -0.21844 -0.35687) (xy -0.22225 -0.34544) (xy -0.22352 -0.33528) (xy -0.22606 -0.32512)
						(xy -0.22733 -0.31369) (xy -0.22733 -0.30353) (xy -0.2286 -0.2921) (xy -0.22733 -0.28067) (xy -0.22733 -0.27051)
						(xy -0.22606 -0.25908) (xy -0.22352 -0.24892) (xy -0.22225 -0.23876) (xy -0.21844 -0.22733) (xy -0.2159 -0.21717)
						(xy -0.21209 -0.20701) (xy -0.20701 -0.19685) (xy -0.2032 -0.18796) (xy -0.19812 -0.1778) (xy -0.17272 -0.14224)
						(xy -0.1651 -0.13462) (xy -0.1651 0.7366) (xy -0.16256 0.76835) (xy -0.1524 0.8001) (xy -0.13716 0.82804)
						(xy -0.11684 0.85344) (xy -0.09144 0.87376) (xy -0.0635 0.889) (xy -0.03175 0.89916) (xy 0 0.9017)
						(xy 0.03175 0.89916) (xy 0.0635 0.889) (xy 0.09144 0.87376) (xy 0.11684 0.85344) (xy 0.13716 0.82804)
						(xy 0.1524 0.8001) (xy 0.16256 0.76835) (xy 0.1651 0.7366) (xy 0.1651 -0.13462) (xy 0.17272 -0.14224)
						(xy 0.19812 -0.1778) (xy 0.2032 -0.18796) (xy 0.20701 -0.19685) (xy 0.21209 -0.20701) (xy 0.2159 -0.21717)
						(xy 0.21844 -0.22733) (xy 0.22225 -0.23876) (xy 0.22352 -0.24892) (xy 0.22606 -0.25908) (xy 0.22733 -0.27051)
						(xy 0.22733 -0.28067) (xy 0.2286 -0.2921) (xy 0.22733 -0.30353) (xy 0.22733 -0.31369) (xy 0.22606 -0.32512)
						(xy 0.22352 -0.33528) (xy 0.22225 -0.34544) (xy 0.21844 -0.35687) (xy 0.2159 -0.36703) (xy 0.21209 -0.37719)
						(xy 0.20701 -0.38735) (xy 0.2032 -0.39624) (xy 0.19812 -0.4064) (xy 0.17272 -0.44196) (xy 0.1651 -0.44958)
						(xy 0.1651 -0.7366) (xy 0.16256 -0.76835) (xy 0.1524 -0.8001) (xy 0.13716 -0.82804) (xy 0.11684 -0.85344)
						(xy 0.09144 -0.87376) (xy 0.0635 -0.889) (xy 0.03175 -0.89916)
					)
					(width 0)
					(fill yes)
				)
			)
		)
		(pad "202" smd custom
			(at 31.049976 4.100068)
			(size 0.1143 0.1143)
			(layers "B.Cu" "B.Mask" "B.Paste")
			(net "SMB_M_A0_R_CLK")
			(options
				(clearance outline)
				(anchor circle)
			)
			(primitives
				(gr_poly
					(pts
						(xy 0 -0.9017) (xy -0.03175 -0.89916) (xy -0.0635 -0.889) (xy -0.09144 -0.87376) (xy -0.11684 -0.85344)
						(xy -0.13716 -0.82804) (xy -0.1524 -0.8001) (xy -0.16256 -0.76835) (xy -0.1651 -0.7366) (xy -0.1651 0.13462)
						(xy -0.17272 0.14224) (xy -0.19812 0.1778) (xy -0.2032 0.18796) (xy -0.20701 0.19685) (xy -0.21209 0.20701)
						(xy -0.2159 0.21717) (xy -0.21844 0.22733) (xy -0.22225 0.23876) (xy -0.22352 0.24892) (xy -0.22606 0.25908)
						(xy -0.22733 0.27051) (xy -0.22733 0.28067) (xy -0.2286 0.2921) (xy -0.22733 0.30353) (xy -0.22733 0.31369)
						(xy -0.22606 0.32512) (xy -0.22352 0.33528) (xy -0.22225 0.34544) (xy -0.21844 0.35687) (xy -0.2159 0.36703)
						(xy -0.21209 0.37719) (xy -0.20701 0.38735) (xy -0.2032 0.39624) (xy -0.19812 0.4064) (xy -0.17272 0.44196)
						(xy -0.1651 0.44958) (xy -0.1651 0.7366) (xy -0.16256 0.76835) (xy -0.1524 0.8001) (xy -0.13716 0.82804)
						(xy -0.11684 0.85344) (xy -0.09144 0.87376) (xy -0.0635 0.889) (xy -0.03175 0.89916) (xy 0 0.9017)
						(xy 0.03175 0.89916) (xy 0.0635 0.889) (xy 0.09144 0.87376) (xy 0.11684 0.85344) (xy 0.13716 0.82804)
						(xy 0.1524 0.8001) (xy 0.16256 0.76835) (xy 0.1651 0.7366) (xy 0.1651 0.44958) (xy 0.17272 0.44196)
						(xy 0.19812 0.4064) (xy 0.2032 0.39624) (xy 0.20701 0.38735) (xy 0.21209 0.37719) (xy 0.2159 0.36703)
						(xy 0.21844 0.35687) (xy 0.22225 0.34544) (xy 0.22352 0.33528) (xy 0.22606 0.32512) (xy 0.22733 0.31369)
						(xy 0.22733 0.30353) (xy 0.2286 0.2921) (xy 0.22733 0.28067) (xy 0.22733 0.27051) (xy 0.22606 0.25908)
						(xy 0.22352 0.24892) (xy 0.22225 0.23876) (xy 0.21844 0.22733) (xy 0.2159 0.21717) (xy 0.21209 0.20701)
						(xy 0.20701 0.19685) (xy 0.2032 0.18796) (xy 0.19812 0.1778) (xy 0.17272 0.14224) (xy 0.1651 0.13462)
						(xy 0.1651 -0.7366) (xy 0.16256 -0.76835) (xy 0.1524 -0.8001) (xy 0.13716 -0.82804) (xy 0.11684 -0.85344)
						(xy 0.09144 -0.87376) (xy 0.0635 -0.889) (xy 0.03175 -0.89916)
					)
					(width 0)
					(fill yes)
				)
			)
		)
	)
)
